(kicad_pcb
	(version 20260206)
	(generator "pcbnew")
	(generator_version "10.0")
	(general
		(thickness 1.6)
		(legacy_teardrops no)
	)
	(paper "A4")
	(title_block
		(title "Bryce Canyon_F.DPB_16315-1-OCP.brd")
		(comment 1 "Bryce Canyon / footprints 1627-1634 of 2223")
	)
	(layers
		(0 "F.Cu" signal "TOP")
		(4 "In1.Cu" signal "L2GND")
		(6 "In2.Cu" signal "L3")
		(8 "In3.Cu" signal "L4GND")
		(10 "In4.Cu" signal "L5")
		(12 "In5.Cu" signal "L6VCC")
		(14 "In6.Cu" signal "L7VCC")
		(16 "In7.Cu" signal "L8")
		(18 "In8.Cu" signal "L9GND")
		(20 "In9.Cu" signal "L10")
		(22 "In10.Cu" signal "L11GND")
		(2 "B.Cu" signal "BOTTOM")
		(9 "F.Adhes" user "F.Adhesive")
		(11 "B.Adhes" user "B.Adhesive")
		(13 "F.Paste" user "Package Geometry/Pastemask Top")
		(15 "B.Paste" user "Package Geometry/Pastemask Bottom")
		(5 "F.SilkS" user "Ref Des/Silkscreen Top")
		(7 "B.SilkS" user "Ref Des/Silkscreen Bottom")
		(1 "F.Mask" user "Board Geometry/Soldermask Top")
		(3 "B.Mask" user "Board Geometry/Soldermask Bottom")
		(17 "Dwgs.User" user "User.Drawings")
		(19 "Cmts.User" user "User.Comments")
		(21 "Eco1.User" user "User.Eco1")
		(23 "Eco2.User" user "User.Eco2")
		(25 "Edge.Cuts" user "Board Geometry/Outline")
		(27 "Margin" user)
		(31 "F.CrtYd" user "Package Geometry/Place Bound Top")
		(29 "B.CrtYd" user "Package Geometry/Place Bound Bottom")
		(35 "F.Fab" user "Ref Des/Assembly Top")
		(33 "B.Fab" user "Ref Des/Assembly Bottom")
	)
	(footprint ""
		(layer "F.Cu")
		(at 395.83995 -48.554894 -90)
		(property "Reference" "R873"
			(at 0 0 270)
			(layer "F.SilkS")
			(hide yes)
			(effects
				(font
					(size 1.27 1.27)
				)
			)
		)
		(property "Value" "4K7R2J-2-GP"
			(at 0.064008 -3.993896 270)
			(unlocked yes)
			(layer "F.Fab")
			(hide yes)
			(effects
				(font
					(size 1.016 1.016)
					(thickness 0.1524)
				)
			)
		)
		(property "Device Type" "R402H16"
			(at 0.064008 -5.517896 270)
			(unlocked yes)
			(layer "F.Fab")
			(hide yes)
			(effects
				(font
					(size 1.016 1.016)
					(thickness 0.1524)
				)
			)
		)
		(duplicate_pad_numbers_are_jumpers no)
		(fp_line
			(start -0.508 -0.9398)
			(end -0.508 0.9398)
			(stroke
				(width 0.1524)
				(type default)
			)
			(layer "F.SilkS")
		)
		(fp_line
			(start 0.508 -0.9398)
			(end -0.508 -0.9398)
			(stroke
				(width 0.1524)
				(type default)
			)
			(layer "F.SilkS")
		)
		(fp_rect
			(start -0.508 0.9398)
			(end 0.508 -0.9398)
			(stroke
				(width 0)
				(type default)
			)
			(fill no)
			(layer "F.CrtYd")
		)
		(fp_rect
			(start -0.508 0.9398)
			(end 0.508 -0.9398)
			(stroke
				(width 0)
				(type default)
			)
			(fill no)
			(layer "F.Fab")
		)
		(pad "1" smd custom
			(at 0 -0.4445 270)
			(size 0.1397 0.1397)
			(layers "F.Cu" "F.Mask" "F.Paste")
			(net "P12V_A")
			(options
				(clearance outline)
				(anchor circle)
			)
			(primitives
				(gr_poly
					(pts
						(arc
							(start -0.1778 -0.2794)
							(mid -0.249642 -0.249642)
							(end -0.2794 -0.1778)
						)
						(arc
							(start -0.2794 0.1778)
							(mid -0.249642 0.249642)
							(end -0.1778 0.2794)
						)
						(arc
							(start 0.1778 0.2794)
							(mid 0.249642 0.249642)
							(end 0.2794 0.1778)
						)
						(arc
							(start 0.2794 -0.1778)
							(mid 0.249642 -0.249642)
							(end 0.1778 -0.2794)
						)
					)
					(width 0)
					(fill yes)
				)
			)
		)
		(pad "2" smd custom
			(at 0 0.4445 270)
			(size 0.1397 0.1397)
			(layers "F.Cu" "F.Mask" "F.Paste")
			(net "SW_HDD_P32")
			(options
				(clearance outline)
				(anchor circle)
			)
			(primitives
				(gr_poly
					(pts
						(arc
							(start -0.1778 -0.2794)
							(mid -0.249642 -0.249642)
							(end -0.2794 -0.1778)
						)
						(arc
							(start -0.2794 0.1778)
							(mid -0.249642 0.249642)
							(end -0.1778 0.2794)
						)
						(arc
							(start 0.1778 0.2794)
							(mid 0.249642 0.249642)
							(end 0.2794 0.1778)
						)
						(arc
							(start 0.2794 -0.1778)
							(mid 0.249642 -0.249642)
							(end 0.1778 -0.2794)
						)
					)
					(width 0)
					(fill yes)
				)
			)
		)
	)
	(footprint ""
		(layer "F.Cu")
		(at 482.489002 -277.750016 -90)
		(property "Reference" "VIA20"
			(at 0 0 270)
			(layer "F.SilkS")
			(hide yes)
			(effects
				(font
					(size 1.27 1.27)
				)
			)
		)
		(property "Value" "100OHM-8L-1D6MM-L18L16-GP"
			(at -3.7211 -4.5085 270)
			(unlocked yes)
			(layer "F.Fab")
			(hide yes)
			(effects
				(font
					(size 1.016 1.016)
					(thickness 0.1524)
				)
			)
		)
		(property "Device Type" "VIA-PCIE-4P-394076"
			(at -3.7211 -6.0325 270)
			(unlocked yes)
			(layer "F.Fab")
			(hide yes)
			(effects
				(font
					(size 1.016 1.016)
					(thickness 0.1524)
				)
			)
		)
		(duplicate_pad_numbers_are_jumpers no)
		(fp_rect
			(start -1.9685 0.381)
			(end 1.9685 -0.381)
			(stroke
				(width 0)
				(type default)
			)
			(fill no)
			(layer "F.CrtYd")
		)
		(fp_rect
			(start -1.9685 0.381)
			(end 1.9685 -0.381)
			(stroke
				(width 0)
				(type default)
			)
			(fill no)
			(layer "F.Fab")
		)
		(pad "1" thru_hole circle
			(at -1.5875 0 270)
			(size 0.508 0.508)
			(drill 0.254)
			(layers "*.Cu" "*.Mask")
			(remove_unused_layers no)
			(net "GND")
			(clearance 0.127)
			(thermal_gap 0.127)
		)
		(pad "2" thru_hole circle
			(at -0.5715 0 270)
			(size 0.508 0.508)
			(drill 0.254)
			(layers "*.Cu" "*.Mask")
			(remove_unused_layers no)
			(net "PHY_DRV_A_TO_SCC_A_11_DP")
			(clearance 0.127)
			(thermal_gap 0.127)
		)
		(pad "3" thru_hole circle
			(at 0.5715 0 270)
			(size 0.508 0.508)
			(drill 0.254)
			(layers "*.Cu" "*.Mask")
			(remove_unused_layers no)
			(net "PHY_DRV_A_TO_SCC_A_11_DN")
			(clearance 0.127)
			(thermal_gap 0.127)
		)
		(pad "4" thru_hole circle
			(at 1.5875 0 270)
			(size 0.508 0.508)
			(drill 0.254)
			(layers "*.Cu" "*.Mask")
			(remove_unused_layers no)
			(net "GND")
			(clearance 0.127)
			(thermal_gap 0.127)
		)
	)
	(footprint ""
		(layer "F.Cu")
		(at 475.906592 -287.818322 -90)
		(property "Reference" "C183"
			(at 0 0 270)
			(layer "F.SilkS")
			(hide yes)
			(effects
				(font
					(size 1.27 1.27)
				)
			)
		)
		(property "Value" "SC1U16V3KX-5GP"
			(at 0 -2.8194 270)
			(unlocked yes)
			(layer "F.Fab")
			(hide yes)
			(effects
				(font
					(size 1.016 1.016)
					(thickness 0.1524)
				)
			)
		)
		(property "Device Type" "C603H36"
			(at 0 -4.3434 270)
			(unlocked yes)
			(layer "F.Fab")
			(hide yes)
			(effects
				(font
					(size 1.016 1.016)
					(thickness 0.1524)
				)
			)
		)
		(duplicate_pad_numbers_are_jumpers no)
		(fp_line
			(start 0.508 0)
			(end -0.508 0)
			(stroke
				(width 0.2032)
				(type default)
			)
			(layer "F.SilkS")
		)
		(fp_rect
			(start -0.5842 1.3335)
			(end 0.5842 -1.3335)
			(stroke
				(width 0)
				(type default)
			)
			(fill no)
			(layer "F.CrtYd")
		)
		(fp_rect
			(start -0.5842 1.3335)
			(end 0.5842 -1.3335)
			(stroke
				(width 0)
				(type default)
			)
			(fill no)
			(layer "F.Fab")
		)
		(pad "1" smd custom
			(at 0 -0.762 270)
			(size 0.2159 0.2159)
			(layers "F.Cu" "F.Mask" "F.Paste")
			(net "P5V_HDD11")
			(options
				(clearance outline)
				(anchor circle)
			)
			(primitives
				(gr_poly
					(pts
						(arc
							(start -0.3302 -0.4318)
							(mid -0.402042 -0.402042)
							(end -0.4318 -0.3302)
						)
						(arc
							(start -0.4318 0.3302)
							(mid -0.402042 0.402042)
							(end -0.3302 0.4318)
						)
						(arc
							(start 0.3302 0.4318)
							(mid 0.402042 0.402042)
							(end 0.4318 0.3302)
						)
						(arc
							(start 0.4318 -0.3302)
							(mid 0.402042 -0.402042)
							(end 0.3302 -0.4318)
						)
					)
					(width 0)
					(fill yes)
				)
			)
		)
		(pad "2" smd custom
			(at 0 0.762 270)
			(size 0.2159 0.2159)
			(layers "F.Cu" "F.Mask" "F.Paste")
			(net "GND")
			(options
				(clearance outline)
				(anchor circle)
			)
			(primitives
				(gr_poly
					(pts
						(arc
							(start -0.3302 -0.4318)
							(mid -0.402042 -0.402042)
							(end -0.4318 -0.3302)
						)
						(arc
							(start -0.4318 0.3302)
							(mid -0.402042 0.402042)
							(end -0.3302 0.4318)
						)
						(arc
							(start 0.3302 0.4318)
							(mid 0.402042 0.402042)
							(end 0.4318 0.3302)
						)
						(arc
							(start 0.4318 -0.3302)
							(mid 0.402042 -0.402042)
							(end 0.3302 -0.4318)
						)
					)
					(width 0)
					(fill yes)
				)
			)
		)
	)
	(footprint ""
		(layer "F.Cu")
		(at 43.323002 -150.12035 -90)
		(property "Reference" "R1237"
			(at 0 0 270)
			(layer "F.SilkS")
			(hide yes)
			(effects
				(font
					(size 1.27 1.27)
				)
			)
		)
		(property "Value" "143KR2F-L-1-GP"
			(at 0.064008 -3.993896 270)
			(unlocked yes)
			(layer "F.Fab")
			(hide yes)
			(effects
				(font
					(size 1.016 1.016)
					(thickness 0.1524)
				)
			)
		)
		(property "Device Type" "R402H16"
			(at 0.064008 -5.517896 270)
			(unlocked yes)
			(layer "F.Fab")
			(hide yes)
			(effects
				(font
					(size 1.016 1.016)
					(thickness 0.1524)
				)
			)
		)
		(duplicate_pad_numbers_are_jumpers no)
		(fp_line
			(start -0.508 -0.9398)
			(end -0.508 0.9398)
			(stroke
				(width 0.1524)
				(type default)
			)
			(layer "F.SilkS")
		)
		(fp_line
			(start 0.508 -0.9398)
			(end -0.508 -0.9398)
			(stroke
				(width 0.1524)
				(type default)
			)
			(layer "F.SilkS")
		)
		(fp_rect
			(start -0.508 0.9398)
			(end 0.508 -0.9398)
			(stroke
				(width 0)
				(type default)
			)
			(fill no)
			(layer "F.CrtYd")
		)
		(fp_rect
			(start -0.508 0.9398)
			(end 0.508 -0.9398)
			(stroke
				(width 0)
				(type default)
			)
			(fill no)
			(layer "F.Fab")
		)
		(pad "1" smd custom
			(at 0 -0.4445 270)
			(size 0.1397 0.1397)
			(layers "F.Cu" "F.Mask" "F.Paste")
			(net "AGND_P5V_B")
			(options
				(clearance outline)
				(anchor circle)
			)
			(primitives
				(gr_poly
					(pts
						(arc
							(start -0.1778 -0.2794)
							(mid -0.249642 -0.249642)
							(end -0.2794 -0.1778)
						)
						(arc
							(start -0.2794 0.1778)
							(mid -0.249642 0.249642)
							(end -0.1778 0.2794)
						)
						(arc
							(start 0.1778 0.2794)
							(mid 0.249642 0.249642)
							(end 0.2794 0.1778)
						)
						(arc
							(start 0.2794 -0.1778)
							(mid 0.249642 -0.249642)
							(end 0.1778 -0.2794)
						)
					)
					(width 0)
					(fill yes)
				)
			)
		)
		(pad "2" smd custom
			(at 0 0.4445 270)
			(size 0.1397 0.1397)
			(layers "F.Cu" "F.Mask" "F.Paste")
			(net "P5V_B_TRIP")
			(options
				(clearance outline)
				(anchor circle)
			)
			(primitives
				(gr_poly
					(pts
						(arc
							(start -0.1778 -0.2794)
							(mid -0.249642 -0.249642)
							(end -0.2794 -0.1778)
						)
						(arc
							(start -0.2794 0.1778)
							(mid -0.249642 0.249642)
							(end -0.1778 0.2794)
						)
						(arc
							(start 0.1778 0.2794)
							(mid 0.249642 0.249642)
							(end 0.2794 0.1778)
						)
						(arc
							(start 0.2794 -0.1778)
							(mid 0.249642 -0.249642)
							(end 0.1778 -0.2794)
						)
					)
					(width 0)
					(fill yes)
				)
			)
		)
	)
	(footprint ""
		(layer "F.Cu")
		(at 351.336102 -42.627042 180)
		(property "Reference" "VIA71"
			(at 0 0 180)
			(layer "F.SilkS")
			(hide yes)
			(effects
				(font
					(size 1.27 1.27)
				)
			)
		)
		(property "Value" "100OHM-8L-1D6MM-L18L16-GP"
			(at -3.7211 -4.5085 180)
			(unlocked yes)
			(layer "F.Fab")
			(hide yes)
			(effects
				(font
					(size 1.016 1.016)
					(thickness 0.1524)
				)
			)
		)
		(property "Device Type" "VIA-PCIE-4P-394076"
			(at -3.7211 -6.0325 180)
			(unlocked yes)
			(layer "F.Fab")
			(hide yes)
			(effects
				(font
					(size 1.016 1.016)
					(thickness 0.1524)
				)
			)
		)
		(duplicate_pad_numbers_are_jumpers no)
		(fp_rect
			(start -1.9685 0.381)
			(end 1.9685 -0.381)
			(stroke
				(width 0)
				(type default)
			)
			(fill no)
			(layer "F.CrtYd")
		)
		(fp_rect
			(start -1.9685 0.381)
			(end 1.9685 -0.381)
			(stroke
				(width 0)
				(type default)
			)
			(fill no)
			(layer "F.Fab")
		)
		(pad "1" thru_hole circle
			(at -1.5875 0 180)
			(size 0.508 0.508)
			(drill 0.254)
			(layers "*.Cu" "*.Mask")
			(remove_unused_layers no)
			(net "GND")
			(clearance 0.127)
			(thermal_gap 0.127)
		)
		(pad "2" thru_hole circle
			(at -0.5715 0 180)
			(size 0.508 0.508)
			(drill 0.254)
			(layers "*.Cu" "*.Mask")
			(remove_unused_layers no)
			(net "PHY_SCC_A_TO_DRV_A_31_DP")
			(clearance 0.127)
			(thermal_gap 0.127)
		)
		(pad "3" thru_hole circle
			(at 0.5715 0 180)
			(size 0.508 0.508)
			(drill 0.254)
			(layers "*.Cu" "*.Mask")
			(remove_unused_layers no)
			(net "PHY_SCC_A_TO_DRV_A_31_DN")
			(clearance 0.127)
			(thermal_gap 0.127)
		)
		(pad "4" thru_hole circle
			(at 1.5875 0 180)
			(size 0.508 0.508)
			(drill 0.254)
			(layers "*.Cu" "*.Mask")
			(remove_unused_layers no)
			(net "GND")
			(clearance 0.127)
			(thermal_gap 0.127)
		)
	)
	(footprint ""
		(layer "F.Cu")
		(at 324.739 -277.750016 -90)
		(property "Reference" "VIA17"
			(at 0 0 270)
			(layer "F.SilkS")
			(hide yes)
			(effects
				(font
					(size 1.27 1.27)
				)
			)
		)
		(property "Value" "100OHM-8L-1D6MM-L18L16-GP"
			(at -3.7211 -4.5085 270)
			(unlocked yes)
			(layer "F.Fab")
			(hide yes)
			(effects
				(font
					(size 1.016 1.016)
					(thickness 0.1524)
				)
			)
		)
		(property "Device Type" "VIA-PCIE-4P-394076"
			(at -3.7211 -6.0325 270)
			(unlocked yes)
			(layer "F.Fab")
			(hide yes)
			(effects
				(font
					(size 1.016 1.016)
					(thickness 0.1524)
				)
			)
		)
		(duplicate_pad_numbers_are_jumpers no)
		(fp_rect
			(start -1.9685 0.381)
			(end 1.9685 -0.381)
			(stroke
				(width 0)
				(type default)
			)
			(fill no)
			(layer "F.CrtYd")
		)
		(fp_rect
			(start -1.9685 0.381)
			(end 1.9685 -0.381)
			(stroke
				(width 0)
				(type default)
			)
			(fill no)
			(layer "F.Fab")
		)
		(pad "1" thru_hole circle
			(at -1.5875 0 270)
			(size 0.508 0.508)
			(drill 0.254)
			(layers "*.Cu" "*.Mask")
			(remove_unused_layers no)
			(net "GND")
			(clearance 0.127)
			(thermal_gap 0.127)
		)
		(pad "2" thru_hole circle
			(at -0.5715 0 270)
			(size 0.508 0.508)
			(drill 0.254)
			(layers "*.Cu" "*.Mask")
			(remove_unused_layers no)
			(net "PHY_DRV_A_TO_SCC_A_6_DP")
			(clearance 0.127)
			(thermal_gap 0.127)
		)
		(pad "3" thru_hole circle
			(at 0.5715 0 270)
			(size 0.508 0.508)
			(drill 0.254)
			(layers "*.Cu" "*.Mask")
			(remove_unused_layers no)
			(net "PHY_DRV_A_TO_SCC_A_6_DN")
			(clearance 0.127)
			(thermal_gap 0.127)
		)
		(pad "4" thru_hole circle
			(at 1.5875 0 270)
			(size 0.508 0.508)
			(drill 0.254)
			(layers "*.Cu" "*.Mask")
			(remove_unused_layers no)
			(net "GND")
			(clearance 0.127)
			(thermal_gap 0.127)
		)
	)
	(footprint ""
		(layer "F.Cu")
		(at 6.35 -304.292 180)
		(property "Reference" "R208"
			(at 0 0 180)
			(layer "F.SilkS")
			(hide yes)
			(effects
				(font
					(size 1.27 1.27)
				)
			)
		)
		(property "Value" "91R3F-1-GP"
			(at -0.0254 -2.5146 180)
			(unlocked yes)
			(layer "F.Fab")
			(hide yes)
			(effects
				(font
					(size 1.016 1.016)
					(thickness 0.1524)
				)
			)
		)
		(property "Device Type" "R603H22"
			(at -0.0254 -4.0386 180)
			(unlocked yes)
			(layer "F.Fab")
			(hide yes)
			(effects
				(font
					(size 1.016 1.016)
					(thickness 0.1524)
				)
			)
		)
		(duplicate_pad_numbers_are_jumpers no)
		(fp_line
			(start 0.2032 0)
			(end 0.4826 0)
			(stroke
				(width 0.2032)
				(type default)
			)
			(layer "F.SilkS")
		)
		(fp_line
			(start -0.4826 0)
			(end -0.2032 0)
			(stroke
				(width 0.2032)
				(type default)
			)
			(layer "F.SilkS")
		)
		(fp_rect
			(start -0.5842 1.3335)
			(end 0.5842 -1.3335)
			(stroke
				(width 0)
				(type default)
			)
			(fill no)
			(layer "F.CrtYd")
		)
		(fp_rect
			(start -0.5842 1.3335)
			(end 0.5842 -1.3335)
			(stroke
				(width 0)
				(type default)
			)
			(fill no)
			(layer "F.Fab")
		)
		(pad "1" smd custom
			(at 0 -0.762 180)
			(size 0.2159 0.2159)
			(layers "F.Cu" "F.Mask" "F.Paste")
			(net "P5V_B")
			(options
				(clearance outline)
				(anchor circle)
			)
			(primitives
				(gr_poly
					(pts
						(arc
							(start -0.3302 -0.4318)
							(mid -0.402042 -0.402042)
							(end -0.4318 -0.3302)
						)
						(arc
							(start -0.4318 0.3302)
							(mid -0.402042 0.402042)
							(end -0.3302 0.4318)
						)
						(arc
							(start 0.3302 0.4318)
							(mid 0.402042 0.402042)
							(end 0.4318 0.3302)
						)
						(arc
							(start 0.4318 -0.3302)
							(mid 0.402042 -0.402042)
							(end 0.3302 -0.4318)
						)
					)
					(width 0)
					(fill yes)
				)
			)
		)
		(pad "2" smd custom
			(at 0 0.762 180)
			(size 0.2159 0.2159)
			(layers "F.Cu" "F.Mask" "F.Paste")
			(net "DRV_ACT_24")
			(options
				(clearance outline)
				(anchor circle)
			)
			(primitives
				(gr_poly
					(pts
						(arc
							(start -0.3302 -0.4318)
							(mid -0.402042 -0.402042)
							(end -0.4318 -0.3302)
						)
						(arc
							(start -0.4318 0.3302)
							(mid -0.402042 0.402042)
							(end -0.3302 0.4318)
						)
						(arc
							(start 0.3302 0.4318)
							(mid 0.402042 0.402042)
							(end 0.4318 0.3302)
						)
						(arc
							(start 0.4318 -0.3302)
							(mid 0.402042 -0.402042)
							(end 0.3302 -0.4318)
						)
					)
					(width 0)
					(fill yes)
				)
			)
		)
	)
	(footprint ""
		(layer "F.Cu")
		(at 409.800044 -94.400116)
		(property "Reference" "FLED22"
			(at 0 0 0)
			(layer "F.SilkS")
			(hide yes)
			(effects
				(font
					(size 1.27 1.27)
				)
			)
		)
		(property "Value" "LED-BY-19-GP"
			(at -2.132076 1.414018 0)
			(unlocked yes)
			(layer "F.Fab")
			(hide yes)
			(effects
				(font
					(size 1.016 1.016)
					(thickness 0.1524)
				)
			)
		)
		(property "Device Type" "LED-1615-4PH26"
			(at -2.132076 -0.109982 0)
			(unlocked yes)
			(layer "F.Fab")
			(hide yes)
			(effects
				(font
					(size 1.016 1.016)
					(thickness 0.1524)
				)
			)
		)
		(duplicate_pad_numbers_are_jumpers no)
		(fp_line
			(start -1.2954 0.254)
			(end -1.2954 1.6002)
			(stroke
				(width 0.508)
				(type default)
			)
			(layer "F.SilkS")
		)
		(fp_line
			(start -1.2954 1.6002)
			(end 1.2954 1.6002)
			(stroke
				(width 0.508)
				(type default)
			)
			(layer "F.SilkS")
		)
		(fp_line
			(start -1.1176 -1.4224)
			(end 1.1176 -1.4224)
			(stroke
				(width 0.1524)
				(type default)
			)
			(layer "F.SilkS")
		)
		(fp_line
			(start -1.1176 1.4224)
			(end -1.1176 -1.4224)
			(stroke
				(width 0.1524)
				(type default)
			)
			(layer "F.SilkS")
		)
		(fp_line
			(start 1.1176 -1.4224)
			(end 1.1176 1.4224)
			(stroke
				(width 0.1524)
				(type default)
			)
			(layer "F.SilkS")
		)
		(fp_line
			(start 1.1176 1.4224)
			(end -1.1176 1.4224)
			(stroke
				(width 0.1524)
				(type default)
			)
			(layer "F.SilkS")
		)
		(fp_line
			(start 1.2954 1.6002)
			(end 1.2954 0.254)
			(stroke
				(width 0.508)
				(type default)
			)
			(layer "F.SilkS")
		)
		(fp_rect
			(start -0.7493 0.8001)
			(end 0.7493 -0.8001)
			(stroke
				(width 0)
				(type default)
			)
			(fill no)
			(layer "F.CrtYd")
		)
		(fp_poly
			(pts
				(xy -1.3716 1.6764) (xy -1.3716 -1.6764) (xy 1.3716 -1.6764) (xy 1.3716 0.0635) (xy 0.7493 0.0635)
				(xy 0.7493 -0.8001) (xy -0.7493 -0.8001) (xy -0.7493 0.8001) (xy 0.7493 0.8001) (xy 0.7493 0.0762)
				(xy 1.3716 0.0762) (xy 1.3716 1.6764)
			)
			(stroke
				(width 0)
				(type default)
			)
			(fill no)
			(layer "F.CrtYd")
		)
		(fp_rect
			(start -1.3716 1.6764)
			(end 1.3716 -1.6764)
			(stroke
				(width 0)
				(type default)
			)
			(fill no)
			(layer "F.Fab")
		)
		(pad "1" smd rect
			(at 0.50038 -0.73025)
			(size 0.7112 0.8636)
			(layers "F.Cu" "F.Mask" "F.Paste")
			(net "DRV_ACT_21")
		)
		(pad "2" smd rect
			(at -0.50038 -0.73025)
			(size 0.7112 0.8636)
			(layers "F.Cu" "F.Mask" "F.Paste")
			(net "FLT_HDD21")
		)
		(pad "3" smd rect
			(at 0.50038 0.73025)
			(size 0.7112 0.8636)
			(layers "F.Cu" "F.Mask" "F.Paste")
			(net "DRV_ACT_21_N")
		)
		(pad "4" smd rect
			(at -0.50038 0.73025)
			(size 0.7112 0.8636)
			(layers "F.Cu" "F.Mask" "F.Paste")
			(net "FLT_HDD21_N")
		)
	)
)
